(kicad_pcb
	(version 20241229)
	(generator "pcbnew")
	(generator_version "9.0")
	(general
		(thickness 1.6)
		(legacy_teardrops no)
	)
	(paper "A4")
	(title_block
		(title "GMSL Deserializer")
		(date "2025-10-09")
		(rev "1.0.4")
		(company "Antmicro Ltd")
		(comment 1 "www.antmicro.com")
		(comment 9 "footprints 148-153 of 235")
	)
	(layers
		(0 "F.Cu" signal)
		(4 "In1.Cu" power)
		(6 "In2.Cu" power)
		(2 "B.Cu" signal)
		(9 "F.Adhes" user "F.Adhesive")
		(11 "B.Adhes" user "B.Adhesive")
		(13 "F.Paste" user)
		(15 "B.Paste" user)
		(5 "F.SilkS" user "F.Silkscreen")
		(7 "B.SilkS" user "B.Silkscreen")
		(1 "F.Mask" user)
		(3 "B.Mask" user)
		(17 "Dwgs.User" user "User.Drawings")
		(19 "Cmts.User" user "User.Comments")
		(21 "Eco1.User" user "User.Eco1")
		(23 "Eco2.User" user "User.Eco2")
		(25 "Edge.Cuts" user)
		(27 "Margin" user)
		(31 "F.CrtYd" user "F.Courtyard")
		(29 "B.CrtYd" user "B.Courtyard")
		(35 "F.Fab" user)
		(33 "B.Fab" user)
	)
	(footprint "antmicro-footprints:R_0402_1005Metric"
		(layer "F.Cu")
		(at 169.418 55.753 90)
		(descr "Resistor SMD 0402")
		(tags "resistor SMD 0402")
		(property "Reference" "R4"
			(at 0.891453 0.244264 270)
			(layer "F.SilkS")
			(effects
				(font
					(size 0.7 0.7)
					(thickness 0.15)
				)
				(justify left bottom)
			)
		)
		(property "Value" "R_10k_0402"
			(at -1.011843 1.772047 90)
			(layer "F.Fab")
			(effects
				(font
					(size 0.7 0.7)
					(thickness 0.15)
				)
				(justify left bottom)
			)
		)
		(property "Datasheet" "https://www.bourns.com/docs/product-datasheets/cr.pdf"
			(at 0 0 90)
			(layer "F.Fab")
			(hide yes)
			(effects
				(font
					(size 1.27 1.27)
					(thickness 0.15)
				)
			)
		)
		(property "Description" "SMD Chip Resistor, 10 kohm, ± 1%, 62.5 mW, 0402 [1005 Metric], Thick Film, General Purpose"
			(at 0 0 90)
			(layer "F.Fab")
			(hide yes)
			(effects
				(font
					(size 1.27 1.27)
					(thickness 0.15)
				)
			)
		)
		(property "Author" "Antmicro"
			(at 225.171 -113.665 0)
			(layer "F.Fab")
			(hide yes)
			(effects
				(font
					(size 1 1)
					(thickness 0.15)
				)
			)
		)
		(property "License" "Apache-2.0"
			(at 225.171 -113.665 0)
			(layer "F.Fab")
			(hide yes)
			(effects
				(font
					(size 1 1)
					(thickness 0.15)
				)
			)
		)
		(property "MPN" "CR0402-FX-1002GLF"
			(at 225.171 -113.665 0)
			(layer "F.Fab")
			(hide yes)
			(effects
				(font
					(size 1 1)
					(thickness 0.15)
				)
			)
		)
		(property "Manufacturer" "Bourns"
			(at 225.171 -113.665 0)
			(layer "F.Fab")
			(hide yes)
			(effects
				(font
					(size 1 1)
					(thickness 0.15)
				)
			)
		)
		(property "Tolerance" "1%"
			(at 225.171 -113.665 0)
			(layer "F.Fab")
			(hide yes)
			(effects
				(font
					(size 1 1)
					(thickness 0.15)
				)
			)
		)
		(property "Val" "10k"
			(at 225.171 -113.665 0)
			(layer "F.Fab")
			(hide yes)
			(effects
				(font
					(size 1 1)
					(thickness 0.15)
				)
			)
		)
		(sheetname "/Connectors/")
		(sheetfile "connectors.kicad_sch")
		(attr smd)
		(fp_rect
			(start -0.925 -0.47)
			(end 0.925 0.47)
			(stroke
				(width 0.05)
				(type default)
			)
			(fill no)
			(layer "F.CrtYd")
		)
		(fp_rect
			(start -0.5 -0.25)
			(end 0.5 0.25)
			(stroke
				(width 0.15)
				(type solid)
			)
			(fill no)
			(layer "F.Fab")
		)
		(pad "1" smd roundrect
			(at -0.48 0 90)
			(size 0.59 0.64)
			(layers "F.Cu" "F.Mask" "F.Paste")
			(roundrect_rratio 0.25)
			(net 1 "GND")
			(pintype "passive")
		)
		(pad "2" smd roundrect
			(at 0.48 0 90)
			(size 0.59 0.64)
			(layers "F.Cu" "F.Mask" "F.Paste")
			(roundrect_rratio 0.25)
			(net 131 "Net-(U2-~{OE})")
			(pintype "passive")
		)
	)
	(footprint "antmicro-footprints:R_0402_1005Metric"
		(layer "F.Cu")
		(at 149.225 75.692 45)
		(descr "Resistor SMD 0402")
		(tags "resistor SMD 0402")
		(property "Reference" "R55"
			(at -1.185394 -0.395131 45)
			(layer "F.SilkS")
			(effects
				(font
					(size 0.7 0.7)
					(thickness 0.15)
				)
				(justify left bottom)
			)
		)
		(property "Value" "R_10k_0402"
			(at -1.011843 1.772046 45)
			(layer "F.Fab")
			(effects
				(font
					(size 0.7 0.7)
					(thickness 0.15)
				)
				(justify left bottom)
			)
		)
		(property "Datasheet" "https://www.bourns.com/docs/product-datasheets/cr.pdf"
			(at 0 0 45)
			(layer "F.Fab")
			(hide yes)
			(effects
				(font
					(size 1.27 1.27)
					(thickness 0.15)
				)
			)
		)
		(property "Description" "SMD Chip Resistor, 10 kohm, ± 1%, 62.5 mW, 0402 [1005 Metric], Thick Film, General Purpose"
			(at 0 0 45)
			(layer "F.Fab")
			(hide yes)
			(effects
				(font
					(size 1.27 1.27)
					(thickness 0.15)
				)
			)
		)
		(property "Author" "Antmicro"
			(at 97.229317 -83.348336 0)
			(layer "F.Fab")
			(hide yes)
			(effects
				(font
					(size 1 1)
					(thickness 0.15)
				)
			)
		)
		(property "License" "Apache-2.0"
			(at 97.229317 -83.348336 0)
			(layer "F.Fab")
			(hide yes)
			(effects
				(font
					(size 1 1)
					(thickness 0.15)
				)
			)
		)
		(property "MPN" "CR0402-FX-1002GLF"
			(at 97.229317 -83.348336 0)
			(layer "F.Fab")
			(hide yes)
			(effects
				(font
					(size 1 1)
					(thickness 0.15)
				)
			)
		)
		(property "Manufacturer" "Bourns"
			(at 97.229317 -83.348336 0)
			(layer "F.Fab")
			(hide yes)
			(effects
				(font
					(size 1 1)
					(thickness 0.15)
				)
			)
		)
		(property "Tolerance" "1%"
			(at 97.229317 -83.348336 0)
			(layer "F.Fab")
			(hide yes)
			(effects
				(font
					(size 1 1)
					(thickness 0.15)
				)
			)
		)
		(property "Val" "10k"
			(at 97.229317 -83.348336 0)
			(layer "F.Fab")
			(hide yes)
			(effects
				(font
					(size 1 1)
					(thickness 0.15)
				)
			)
		)
		(sheetname "/Deserializer/")
		(sheetfile "deserializer.kicad_sch")
		(attr smd)
		(fp_poly
			(pts
				(xy -0.925 -0.47) (xy 0.925 -0.47) (xy 0.925 0.47) (xy -0.925 0.47)
			)
			(stroke
				(width 0.05)
				(type default)
			)
			(fill no)
			(layer "F.CrtYd")
		)
		(fp_poly
			(pts
				(xy -0.5 -0.25) (xy 0.5 -0.25) (xy 0.5 0.25) (xy -0.5 0.25)
			)
			(stroke
				(width 0.15)
				(type solid)
			)
			(fill no)
			(layer "F.Fab")
		)
		(pad "1" smd roundrect
			(at -0.48 0 45)
			(size 0.59 0.64)
			(layers "F.Cu" "F.Mask" "F.Paste")
			(roundrect_rratio 0.25)
			(net 79 "/Deserializer/PWDNB")
			(pintype "passive")
		)
		(pad "2" smd roundrect
			(at 0.48 0 45)
			(size 0.59 0.64)
			(layers "F.Cu" "F.Mask" "F.Paste")
			(roundrect_rratio 0.25)
			(net 146 "VDDIO")
			(pintype "passive")
		)
	)
	(footprint "antmicro-footprints:L_Coilcraft-MSS6132T"
		(layer "F.Cu")
		(at 157.988 61.976 90)
		(property "Reference" "L4"
			(at -0.635 -3.531 90)
			(layer "F.SilkS")
			(effects
				(font
					(size 0.7 0.7)
					(thickness 0.15)
				)
				(justify left bottom)
			)
		)
		(property "Value" "L_22u_1.12A_Coilcraft-MSS6132T"
			(at -0.508 4.826 90)
			(layer "F.Fab")
			(effects
				(font
					(size 0.7 0.7)
					(thickness 0.15)
				)
				(justify left bottom)
			)
		)
		(property "Datasheet" "https://www.coilcraft.com/getmedia/d035c9b3-191d-46aa-ab3f-5c1a849157c1/mss6132t.pdf"
			(at 0 0 90)
			(layer "F.Fab")
			(hide yes)
			(effects
				(font
					(size 1.27 1.27)
					(thickness 0.15)
				)
			)
		)
		(property "Description" "Power Inductor (SMT), 22 µH, 1.85 A, Shielded, 2.45 A, WE-MAPI"
			(at 0 0 90)
			(layer "F.Fab")
			(hide yes)
			(effects
				(font
					(size 1.27 1.27)
					(thickness 0.15)
				)
			)
		)
		(property "Author" "Antmicro"
			(at 219.964 -96.012 0)
			(layer "F.Fab")
			(hide yes)
			(effects
				(font
					(size 1 1)
					(thickness 0.15)
				)
			)
		)
		(property "IMax" "1.45A"
			(at 219.964 -96.012 0)
			(layer "F.Fab")
			(hide yes)
			(effects
				(font
					(size 1 1)
					(thickness 0.15)
				)
			)
		)
		(property "ISat" "1.12A"
			(at 219.964 -96.012 0)
			(layer "F.Fab")
			(hide yes)
			(effects
				(font
					(size 1 1)
					(thickness 0.15)
				)
			)
		)
		(property "License" "Apache-2.0"
			(at 219.964 -96.012 0)
			(layer "F.Fab")
			(hide yes)
			(effects
				(font
					(size 1 1)
					(thickness 0.15)
				)
			)
		)
		(property "MPN" "MSS6132T-223"
			(at 219.964 -96.012 0)
			(layer "F.Fab")
			(hide yes)
			(effects
				(font
					(size 1 1)
					(thickness 0.15)
				)
			)
		)
		(property "Manufacturer" "Coilcraft"
			(at 219.964 -96.012 0)
			(layer "F.Fab")
			(hide yes)
			(effects
				(font
					(size 1 1)
					(thickness 0.15)
				)
			)
		)
		(property "Size" "6.1x6.1"
			(at 219.964 -96.012 0)
			(layer "F.Fab")
			(hide yes)
			(effects
				(font
					(size 1 1)
					(thickness 0.15)
				)
			)
		)
		(property "Val" "22u/1.12A"
			(at 219.964 -96.012 0)
			(layer "F.Fab")
			(hide yes)
			(effects
				(font
					(size 1 1)
					(thickness 0.15)
				)
			)
		)
		(sheetname "/Power/")
		(sheetfile "power.kicad_sch")
		(attr smd)
		(fp_line
			(start -0.8 -3.05)
			(end 0.8 -3.05)
			(stroke
				(width 0.15)
				(type solid)
			)
			(layer "F.SilkS")
		)
		(fp_line
			(start -0.8 3.05)
			(end 0.8 3.05)
			(stroke
				(width 0.15)
				(type solid)
			)
			(layer "F.SilkS")
		)
		(fp_rect
			(start -3.35 -3.35)
			(end 3.35 3.35)
			(stroke
				(width 0.05)
				(type solid)
			)
			(fill no)
			(layer "F.CrtYd")
		)
		(fp_rect
			(start -3.1 -3.1)
			(end 3.1 3.1)
			(stroke
				(width 0.15)
				(type solid)
			)
			(fill no)
			(layer "F.Fab")
		)
		(pad "1" smd custom
			(at -2.71 0 180)
			(size 6 0.575)
			(layers "F.Cu" "F.Mask" "F.Paste")
			(net 4 "+12V")
			(pintype "passive")
			(options
				(clearance outline)
				(anchor rect)
			)
			(primitives
				(gr_poly
					(pts
						(xy 2.4 1.71) (xy 2.117646 1.21) (xy 1.9 0.96) (xy 1.65 0.71) (xy 1.2 0.41) (xy 0.4 0.11) (xy 0.4 0.01)
						(xy 2.9 0) (xy 2.9 1.71)
					)
					(width 0.2)
					(fill yes)
				)
				(gr_poly
					(pts
						(xy -2.4 1.731128) (xy -2.117646 1.231128) (xy -1.9 0.981128) (xy -1.65 0.731128) (xy -1.2 0.431128)
						(xy -0.4 0.131128) (xy -0.4 0.031128) (xy -2.9 0.021128) (xy -2.9 1.731128)
					)
					(width 0.2)
					(fill yes)
				)
			)
		)
		(pad "2" smd custom
			(at 2.71 0)
			(size 6 0.575)
			(layers "F.Cu" "F.Mask" "F.Paste")
			(net 54 "Net-(L4-Pad2)")
			(pintype "passive")
			(options
				(clearance outline)
				(anchor rect)
			)
			(primitives
				(gr_poly
					(pts
						(xy -2.4 1.731128) (xy -2.117646 1.231128) (xy -1.9 0.981128) (xy -1.65 0.731128) (xy -1.2 0.431128)
						(xy -0.4 0.131128) (xy -0.4 0.031128) (xy -2.9 0.021128) (xy -2.9 1.731128)
					)
					(width 0.2)
					(fill yes)
				)
				(gr_poly
					(pts
						(xy 2.4 1.71) (xy 2.117646 1.21) (xy 1.9 0.96) (xy 1.65 0.71) (xy 1.2 0.41) (xy 0.4 0.11) (xy 0.4 0.01)
						(xy 2.9 0) (xy 2.9 1.71)
					)
					(width 0.2)
					(fill yes)
				)
			)
		)
	)
	(footprint "antmicro-footprints:L_Coilcraft-PFL1609"
		(layer "F.Cu")
		(at 149.098 53.594)
		(property "Reference" "L11"
			(at -3.153254 0.380655 0)
			(layer "F.SilkS")
			(effects
				(font
					(size 0.7 0.7)
					(thickness 0.15)
				)
				(justify left bottom)
			)
		)
		(property "Value" "L_470n_1A_Coilcraft-PFL1609"
			(at 0 2 0)
			(layer "F.Fab")
			(effects
				(font
					(size 0.7 0.7)
					(thickness 0.15)
				)
				(justify left bottom)
			)
		)
		(property "Datasheet" "https://www.coilcraft.com/getmedia/2f4cd442-d64d-4413-a518-12fcfd03318d/pfl1609.pdf"
			(at 0 0 0)
			(layer "F.Fab")
			(hide yes)
			(effects
				(font
					(size 1.27 1.27)
					(thickness 0.15)
				)
			)
		)
		(property "Description" "Power Inductor (SMT), 6.8 µH, 9.2 A, Shielded, 12.8 A, XAL7070"
			(at 0 0 0)
			(layer "F.Fab")
			(hide yes)
			(effects
				(font
					(size 1.27 1.27)
					(thickness 0.15)
				)
			)
		)
		(property "Author" "Antmicro"
			(at 0 0 0)
			(layer "F.Fab")
			(hide yes)
			(effects
				(font
					(size 1 1)
					(thickness 0.15)
				)
			)
		)
		(property "IMax" "1 A"
			(at 0 0 0)
			(layer "F.Fab")
			(hide yes)
			(effects
				(font
					(size 1 1)
					(thickness 0.15)
				)
			)
		)
		(property "ISat" "0.99 A"
			(at 0 0 0)
			(layer "F.Fab")
			(hide yes)
			(effects
				(font
					(size 1 1)
					(thickness 0.15)
				)
			)
		)
		(property "License" "Apache-2.0"
			(at 0 0 0)
			(layer "F.Fab")
			(hide yes)
			(effects
				(font
					(size 1 1)
					(thickness 0.15)
				)
			)
		)
		(property "MPN" "PFL1609-471"
			(at 0 0 0)
			(layer "F.Fab")
			(hide yes)
			(effects
				(font
					(size 1 1)
					(thickness 0.15)
				)
			)
		)
		(property "Manufacturer" "Coilcraft"
			(at 0 0 0)
			(layer "F.Fab")
			(hide yes)
			(effects
				(font
					(size 1 1)
					(thickness 0.15)
				)
			)
		)
		(property "Size" "1.07x1.8"
			(at 0 0 0)
			(layer "F.Fab")
			(hide yes)
			(effects
				(font
					(size 1 1)
					(thickness 0.15)
				)
			)
		)
		(property "Val" "470n/0.99A"
			(at 0 0 0)
			(layer "F.Fab")
			(hide yes)
			(effects
				(font
					(size 1 1)
					(thickness 0.15)
				)
			)
		)
		(sheetname "/Power/")
		(sheetfile "power.kicad_sch")
		(attr smd)
		(fp_line
			(start -0.23 -0.45)
			(end 0.23 -0.45)
			(stroke
				(width 0.15)
				(type solid)
			)
			(layer "F.SilkS")
		)
		(fp_line
			(start -0.23 0.45)
			(end 0.23 0.45)
			(stroke
				(width 0.15)
				(type solid)
			)
			(layer "F.SilkS")
		)
		(fp_rect
			(start -1.2 -0.84)
			(end 1.2 0.84)
			(stroke
				(width 0.05)
				(type solid)
			)
			(fill no)
			(layer "F.CrtYd")
		)
		(fp_rect
			(start -0.9 -0.535)
			(end 0.9 0.535)
			(stroke
				(width 0.15)
				(type solid)
			)
			(fill no)
			(layer "F.Fab")
		)
		(pad "1" smd roundrect
			(at -0.635 0)
			(size 0.64 1.02)
			(layers "F.Cu" "F.Mask" "F.Paste")
			(roundrect_rratio 0.15)
			(net 57 "Net-(L11-Pad1)")
			(pintype "passive")
		)
		(pad "2" smd roundrect
			(at 0.635 0)
			(size 0.64 1.02)
			(layers "F.Cu" "F.Mask" "F.Paste")
			(roundrect_rratio 0.15)
			(net 61 "Net-(L11-Pad2)")
			(pintype "passive")
		)
	)
	(footprint "antmicro-footprints:R_0402_1005Metric"
		(layer "F.Cu")
		(at 166.116 59.817 90)
		(descr "Resistor SMD 0402")
		(tags "resistor SMD 0402")
		(property "Reference" "R6"
			(at -2.286 0.381 90)
			(layer "F.SilkS")
			(effects
				(font
					(size 0.7 0.7)
					(thickness 0.15)
				)
				(justify left bottom)
			)
		)
		(property "Value" "R_0R_0402"
			(at -1.011843 1.772047 90)
			(layer "F.Fab")
			(effects
				(font
					(size 0.7 0.7)
					(thickness 0.15)
				)
				(justify left bottom)
			)
		)
		(property "Datasheet" "https://industrial.panasonic.com/cdbs/www-data/pdf/RDA0000/AOA0000C301.pdf"
			(at 0 0 90)
			(layer "F.Fab")
			(hide yes)
			(effects
				(font
					(size 1.27 1.27)
					(thickness 0.15)
				)
			)
		)
		(property "Description" "SMD Chip Resistor, Jumper, 0 ohm, 100 mW, 0402 [1005 Metric], Thick Film, General Purpose"
			(at 0 0 90)
			(layer "F.Fab")
			(hide yes)
			(effects
				(font
					(size 1.27 1.27)
					(thickness 0.15)
				)
			)
		)
		(property "Author" "Antmicro"
			(at 225.933 -106.299 0)
			(layer "F.Fab")
			(hide yes)
			(effects
				(font
					(size 1 1)
					(thickness 0.15)
				)
			)
		)
		(property "Current" "1A"
			(at 225.933 -106.299 0)
			(layer "F.Fab")
			(hide yes)
			(effects
				(font
					(size 1 1)
					(thickness 0.15)
				)
			)
		)
		(property "License" "Apache-2.0"
			(at 225.933 -106.299 0)
			(layer "F.Fab")
			(hide yes)
			(effects
				(font
					(size 1 1)
					(thickness 0.15)
				)
			)
		)
		(property "MPN" "ERJ2GE0R00X"
			(at 225.933 -106.299 0)
			(layer "F.Fab")
			(hide yes)
			(effects
				(font
					(size 1 1)
					(thickness 0.15)
				)
			)
		)
		(property "Manufacturer" "Panasonic"
			(at 225.933 -106.299 0)
			(layer "F.Fab")
			(hide yes)
			(effects
				(font
					(size 1 1)
					(thickness 0.15)
				)
			)
		)
		(property "Tolerance" ""
			(at 225.933 -106.299 0)
			(layer "F.Fab")
			(hide yes)
			(effects
				(font
					(size 1 1)
					(thickness 0.15)
				)
			)
		)
		(property "Val" "0R"
			(at 225.933 -106.299 0)
			(layer "F.Fab")
			(hide yes)
			(effects
				(font
					(size 1 1)
					(thickness 0.15)
				)
			)
		)
		(sheetname "/Connectors/")
		(sheetfile "connectors.kicad_sch")
		(attr smd)
		(fp_rect
			(start -0.925 -0.47)
			(end 0.925 0.47)
			(stroke
				(width 0.05)
				(type default)
			)
			(fill no)
			(layer "F.CrtYd")
		)
		(fp_rect
			(start -0.5 -0.25)
			(end 0.5 0.25)
			(stroke
				(width 0.15)
				(type solid)
			)
			(fill no)
			(layer "F.Fab")
		)
		(pad "1" smd roundrect
			(at -0.48 0 90)
			(size 0.59 0.64)
			(layers "F.Cu" "F.Mask" "F.Paste")
			(roundrect_rratio 0.25)
			(net 83 "/Connectors/MFP3")
			(pintype "passive")
		)
		(pad "2" smd roundrect
			(at 0.48 0 90)
			(size 0.59 0.64)
			(layers "F.Cu" "F.Mask" "F.Paste")
			(roundrect_rratio 0.25)
			(net 132 "Net-(U2-Y)")
			(pintype "passive")
		)
	)
	(footprint "antmicro-footprints:R_0402_1005Metric"
		(layer "F.Cu")
		(at 150.622 56.642 90)
		(descr "Resistor SMD 0402")
		(tags "resistor SMD 0402")
		(property "Reference" "R26"
			(at -1.016 1.262 90)
			(layer "F.SilkS")
			(effects
				(font
					(size 0.7 0.7)
					(thickness 0.15)
				)
				(justify left bottom)
			)
		)
		(property "Value" "R_5k1_0402"
			(at -1.011843 1.772047 90)
			(layer "F.Fab")
			(effects
				(font
					(size 0.7 0.7)
					(thickness 0.15)
				)
				(justify left bottom)
			)
		)
		(property "Datasheet" "https://www.bourns.com/docs/product-datasheets/cr.pdf"
			(at 0 0 90)
			(layer "F.Fab")
			(hide yes)
			(effects
				(font
					(size 1.27 1.27)
					(thickness 0.15)
				)
			)
		)
		(property "Description" "SMD Chip Resistor, 5.1 kohm, ± 1%, 63 mW, 0402 [1005 Metric], Thick Film, General Purpose"
			(at 0 0 90)
			(layer "F.Fab")
			(hide yes)
			(effects
				(font
					(size 1.27 1.27)
					(thickness 0.15)
				)
			)
		)
		(property "Author" "Antmicro"
			(at 207.264 -93.98 0)
			(layer "F.Fab")
			(hide yes)
			(effects
				(font
					(size 1 1)
					(thickness 0.15)
				)
			)
		)
		(property "License" "Apache-2.0"
			(at 207.264 -93.98 0)
			(layer "F.Fab")
			(hide yes)
			(effects
				(font
					(size 1 1)
					(thickness 0.15)
				)
			)
		)
		(property "MPN" "CR0402-FX-5101GLF"
			(at 207.264 -93.98 0)
			(layer "F.Fab")
			(hide yes)
			(effects
				(font
					(size 1 1)
					(thickness 0.15)
				)
			)
		)
		(property "Manufacturer" "Bourns"
			(at 207.264 -93.98 0)
			(layer "F.Fab")
			(hide yes)
			(effects
				(font
					(size 1 1)
					(thickness 0.15)
				)
			)
		)
		(property "Tolerance" "1%"
			(at 207.264 -93.98 0)
			(layer "F.Fab")
			(hide yes)
			(effects
				(font
					(size 1 1)
					(thickness 0.15)
				)
			)
		)
		(property "Val" "5k1"
			(at 207.264 -93.98 0)
			(layer "F.Fab")
			(hide yes)
			(effects
				(font
					(size 1 1)
					(thickness 0.15)
				)
			)
		)
		(sheetname "/Power/")
		(sheetfile "power.kicad_sch")
		(attr smd)
		(fp_rect
			(start -0.925 -0.47)
			(end 0.925 0.47)
			(stroke
				(width 0.05)
				(type default)
			)
			(fill no)
			(layer "F.CrtYd")
		)
		(fp_rect
			(start -0.5 -0.25)
			(end 0.5 0.25)
			(stroke
				(width 0.15)
				(type solid)
			)
			(fill no)
			(layer "F.Fab")
		)
		(pad "1" smd roundrect
			(at -0.48 0 90)
			(size 0.59 0.64)
			(layers "F.Cu" "F.Mask" "F.Paste")
			(roundrect_rratio 0.25)
			(net 53 "Net-(L3-Pad2)")
			(pintype "passive")
		)
		(pad "2" smd roundrect
			(at 0.48 0 90)
			(size 0.59 0.64)
			(layers "F.Cu" "F.Mask" "F.Paste")
			(roundrect_rratio 0.25)
			(net 57 "Net-(L11-Pad1)")
			(pintype "passive")
		)
	)
)
